(kicad_pcb
	(version 20260206)
	(generator "pcbnew")
	(generator_version "10.0")
	(general
		(thickness 1.6)
		(legacy_teardrops no)
	)
	(paper "A4")
	(title_block
		(title "03242023_DA0F0TMBIJ0_F0T_Motherboard_J_brd_V01_OCP.brd")
		(comment 1 "Grand Teton / footprints 2299-2305 of 6105")
	)
	(layers
		(0 "F.Cu" signal "TOP")
		(4 "In1.Cu" signal "GND")
		(6 "In2.Cu" signal "IN1")
		(8 "In3.Cu" signal "GND1")
		(10 "In4.Cu" signal "IN2")
		(12 "In5.Cu" signal "GND2")
		(14 "In6.Cu" signal "IN3")
		(16 "In7.Cu" signal "GND3")
		(18 "In8.Cu" signal "VCC")
		(20 "In9.Cu" signal "VCC1")
		(22 "In10.Cu" signal "GND4")
		(24 "In11.Cu" signal "IN4")
		(26 "In12.Cu" signal "GND5")
		(28 "In13.Cu" signal "IN5")
		(30 "In14.Cu" signal "GND6")
		(32 "In15.Cu" signal "IN6")
		(34 "In16.Cu" signal "GND7")
		(2 "B.Cu" signal "BOTTOM")
		(9 "F.Adhes" user "F.Adhesive")
		(11 "B.Adhes" user "B.Adhesive")
		(13 "F.Paste" user "Package Geometry/Pastemask Top")
		(15 "B.Paste" user "Package Geometry/Pastemask Bottom")
		(5 "F.SilkS" user "Ref Des/Silkscreen Top")
		(7 "B.SilkS" user "Ref Des/Silkscreen Bottom")
		(1 "F.Mask" user "Board Geometry/Soldermask Top")
		(3 "B.Mask" user "Board Geometry/Soldermask Bottom")
		(17 "Dwgs.User" user "User.Drawings")
		(19 "Cmts.User" user "User.Comments")
		(21 "Eco1.User" user "User.Eco1")
		(23 "Eco2.User" user "User.Eco2")
		(25 "Edge.Cuts" user "Board Geometry/Outline")
		(27 "Margin" user)
		(31 "F.CrtYd" user "Package Geometry/Place Bound Top")
		(29 "B.CrtYd" user "Package Geometry/Place Bound Bottom")
		(35 "F.Fab" user "Ref Des/Assembly Top")
		(33 "B.Fab" user "Ref Des/Assembly Bottom")
	)
	(footprint ""
		(layer "F.Cu")
		(at 418.485828 -183.032654)
		(property "Reference" "PC188"
			(at 0 0 0)
			(layer "F.SilkS")
			(hide yes)
			(effects
				(font
					(size 1.27 1.27)
				)
			)
		)
		(property "Value" ""
			(at 0 0 0)
			(layer "F.Fab")
			(effects
				(font
					(size 1.27 1.27)
				)
			)
		)
		(duplicate_pad_numbers_are_jumpers no)
		(fp_line
			(start -0.7874 -0.4064)
			(end 0.7874 -0.4064)
			(stroke
				(width 0.1524)
				(type default)
			)
			(layer "F.SilkS")
		)
		(fp_line
			(start -0.7874 0.4064)
			(end -0.7874 -0.4064)
			(stroke
				(width 0.1524)
				(type default)
			)
			(layer "F.SilkS")
		)
		(fp_line
			(start 0.7874 -0.4064)
			(end 0.7874 0.4064)
			(stroke
				(width 0.1524)
				(type default)
			)
			(layer "F.SilkS")
		)
		(fp_line
			(start 0.7874 0.4064)
			(end -0.7874 0.4064)
			(stroke
				(width 0.1524)
				(type default)
			)
			(layer "F.SilkS")
		)
		(fp_line
			(start -0.67945 -0.305054)
			(end -0.12065 -0.305054)
			(stroke
				(width 0.1)
				(type default)
			)
			(layer "F.Fab")
		)
		(fp_line
			(start -0.67945 0.3048)
			(end -0.67945 -0.305054)
			(stroke
				(width 0.1)
				(type default)
			)
			(layer "F.Fab")
		)
		(fp_line
			(start -0.12065 -0.305054)
			(end -0.12065 -0.2794)
			(stroke
				(width 0.1)
				(type default)
			)
			(layer "F.Fab")
		)
		(fp_line
			(start -0.12065 -0.2794)
			(end 0.12065 -0.2794)
			(stroke
				(width 0.1)
				(type default)
			)
			(layer "F.Fab")
		)
		(fp_line
			(start -0.12065 0.2794)
			(end -0.12065 0.3048)
			(stroke
				(width 0.1)
				(type default)
			)
			(layer "F.Fab")
		)
		(fp_line
			(start -0.12065 0.3048)
			(end -0.67945 0.3048)
			(stroke
				(width 0.1)
				(type default)
			)
			(layer "F.Fab")
		)
		(fp_line
			(start 0.120396 0.2794)
			(end -0.12065 0.2794)
			(stroke
				(width 0.1)
				(type default)
			)
			(layer "F.Fab")
		)
		(fp_line
			(start 0.120396 0.3048)
			(end 0.120396 0.2794)
			(stroke
				(width 0.1)
				(type default)
			)
			(layer "F.Fab")
		)
		(fp_line
			(start 0.12065 -0.3048)
			(end 0.67945 -0.3048)
			(stroke
				(width 0.1)
				(type default)
			)
			(layer "F.Fab")
		)
		(fp_line
			(start 0.12065 -0.2794)
			(end 0.12065 -0.3048)
			(stroke
				(width 0.1)
				(type default)
			)
			(layer "F.Fab")
		)
		(fp_line
			(start 0.67945 -0.3048)
			(end 0.67945 0.3048)
			(stroke
				(width 0.1)
				(type default)
			)
			(layer "F.Fab")
		)
		(fp_line
			(start 0.67945 0.3048)
			(end 0.120396 0.3048)
			(stroke
				(width 0.1)
				(type default)
			)
			(layer "F.Fab")
		)
		(pad "1" smd circle
			(at -0.40005 0)
			(size 0 0)
			(layers "F.Cu" "F.Mask" "F.Paste")
			(net "PVCCINFAON_CPU0_VDD2")
		)
		(pad "2" smd circle
			(at 0.40005 0)
			(size 0 0)
			(layers "F.Cu" "F.Mask" "F.Paste")
			(net "GND")
		)
	)
	(footprint ""
		(layer "F.Cu")
		(at 398.270476 -148.010118 90)
		(property "Reference" "PR522"
			(at 0 0 90)
			(layer "F.SilkS")
			(hide yes)
			(effects
				(font
					(size 1.27 1.27)
				)
			)
		)
		(property "Value" ""
			(at 0 0 90)
			(layer "F.Fab")
			(effects
				(font
					(size 1.27 1.27)
				)
			)
		)
		(duplicate_pad_numbers_are_jumpers no)
		(fp_line
			(start 0.7874 -0.4064)
			(end 0.7874 0.4064)
			(stroke
				(width 0.1524)
				(type default)
			)
			(layer "F.SilkS")
		)
		(fp_line
			(start -0.7874 -0.4064)
			(end 0.7874 -0.4064)
			(stroke
				(width 0.1524)
				(type default)
			)
			(layer "F.SilkS")
		)
		(fp_line
			(start 0.7874 0.4064)
			(end -0.7874 0.4064)
			(stroke
				(width 0.1524)
				(type default)
			)
			(layer "F.SilkS")
		)
		(fp_line
			(start -0.7874 0.4064)
			(end -0.7874 -0.4064)
			(stroke
				(width 0.1524)
				(type default)
			)
			(layer "F.SilkS")
		)
		(fp_line
			(start -0.12065 -0.305054)
			(end -0.12065 -0.2794)
			(stroke
				(width 0.1)
				(type default)
			)
			(layer "F.Fab")
		)
		(fp_line
			(start -0.67945 -0.305054)
			(end -0.12065 -0.305054)
			(stroke
				(width 0.1)
				(type default)
			)
			(layer "F.Fab")
		)
		(fp_line
			(start 0.67945 -0.3048)
			(end 0.67945 0.3048)
			(stroke
				(width 0.1)
				(type default)
			)
			(layer "F.Fab")
		)
		(fp_line
			(start 0.12065 -0.3048)
			(end 0.67945 -0.3048)
			(stroke
				(width 0.1)
				(type default)
			)
			(layer "F.Fab")
		)
		(fp_line
			(start 0.12065 -0.2794)
			(end 0.12065 -0.3048)
			(stroke
				(width 0.1)
				(type default)
			)
			(layer "F.Fab")
		)
		(fp_line
			(start -0.12065 -0.2794)
			(end 0.12065 -0.2794)
			(stroke
				(width 0.1)
				(type default)
			)
			(layer "F.Fab")
		)
		(fp_line
			(start 0.120396 0.2794)
			(end -0.12065 0.2794)
			(stroke
				(width 0.1)
				(type default)
			)
			(layer "F.Fab")
		)
		(fp_line
			(start -0.12065 0.2794)
			(end -0.12065 0.3048)
			(stroke
				(width 0.1)
				(type default)
			)
			(layer "F.Fab")
		)
		(fp_line
			(start 0.67945 0.3048)
			(end 0.120396 0.3048)
			(stroke
				(width 0.1)
				(type default)
			)
			(layer "F.Fab")
		)
		(fp_line
			(start 0.120396 0.3048)
			(end 0.120396 0.2794)
			(stroke
				(width 0.1)
				(type default)
			)
			(layer "F.Fab")
		)
		(fp_line
			(start -0.12065 0.3048)
			(end -0.67945 0.3048)
			(stroke
				(width 0.1)
				(type default)
			)
			(layer "F.Fab")
		)
		(fp_line
			(start -0.67945 0.3048)
			(end -0.67945 -0.305054)
			(stroke
				(width 0.1)
				(type default)
			)
			(layer "F.Fab")
		)
		(pad "1" smd circle
			(at -0.40005 0 90)
			(size 0 0)
			(layers "F.Cu" "F.Mask" "F.Paste")
			(net "VSENSE_PVCCFA_EHV_CPU0_DP")
		)
		(pad "2" smd circle
			(at 0.40005 0 90)
			(size 0 0)
			(layers "F.Cu" "F.Mask" "F.Paste")
			(net "PVCCFA_EHV_CPU0")
		)
	)
	(footprint ""
		(layer "F.Cu")
		(at 108.05668 -61.102748)
		(property "Reference" "R1365"
			(at 0 0 0)
			(layer "F.SilkS")
			(hide yes)
			(effects
				(font
					(size 1.27 1.27)
				)
			)
		)
		(property "Value" ""
			(at 0 0 0)
			(layer "F.Fab")
			(effects
				(font
					(size 1.27 1.27)
				)
			)
		)
		(duplicate_pad_numbers_are_jumpers no)
		(fp_line
			(start -0.7874 -0.4064)
			(end 0.7874 -0.4064)
			(stroke
				(width 0.1524)
				(type default)
			)
			(layer "F.SilkS")
		)
		(fp_line
			(start -0.7874 0.4064)
			(end -0.7874 -0.4064)
			(stroke
				(width 0.1524)
				(type default)
			)
			(layer "F.SilkS")
		)
		(fp_line
			(start 0.7874 -0.4064)
			(end 0.7874 0.4064)
			(stroke
				(width 0.1524)
				(type default)
			)
			(layer "F.SilkS")
		)
		(fp_line
			(start 0.7874 0.4064)
			(end -0.7874 0.4064)
			(stroke
				(width 0.1524)
				(type default)
			)
			(layer "F.SilkS")
		)
		(fp_line
			(start -0.67945 -0.305054)
			(end -0.12065 -0.305054)
			(stroke
				(width 0.1)
				(type default)
			)
			(layer "F.Fab")
		)
		(fp_line
			(start -0.67945 0.3048)
			(end -0.67945 -0.305054)
			(stroke
				(width 0.1)
				(type default)
			)
			(layer "F.Fab")
		)
		(fp_line
			(start -0.12065 -0.305054)
			(end -0.12065 -0.2794)
			(stroke
				(width 0.1)
				(type default)
			)
			(layer "F.Fab")
		)
		(fp_line
			(start -0.12065 -0.2794)
			(end 0.12065 -0.2794)
			(stroke
				(width 0.1)
				(type default)
			)
			(layer "F.Fab")
		)
		(fp_line
			(start -0.12065 0.2794)
			(end -0.12065 0.3048)
			(stroke
				(width 0.1)
				(type default)
			)
			(layer "F.Fab")
		)
		(fp_line
			(start -0.12065 0.3048)
			(end -0.67945 0.3048)
			(stroke
				(width 0.1)
				(type default)
			)
			(layer "F.Fab")
		)
		(fp_line
			(start 0.120396 0.2794)
			(end -0.12065 0.2794)
			(stroke
				(width 0.1)
				(type default)
			)
			(layer "F.Fab")
		)
		(fp_line
			(start 0.120396 0.3048)
			(end 0.120396 0.2794)
			(stroke
				(width 0.1)
				(type default)
			)
			(layer "F.Fab")
		)
		(fp_line
			(start 0.12065 -0.3048)
			(end 0.67945 -0.3048)
			(stroke
				(width 0.1)
				(type default)
			)
			(layer "F.Fab")
		)
		(fp_line
			(start 0.12065 -0.2794)
			(end 0.12065 -0.3048)
			(stroke
				(width 0.1)
				(type default)
			)
			(layer "F.Fab")
		)
		(fp_line
			(start 0.67945 -0.3048)
			(end 0.67945 0.3048)
			(stroke
				(width 0.1)
				(type default)
			)
			(layer "F.Fab")
		)
		(fp_line
			(start 0.67945 0.3048)
			(end 0.120396 0.3048)
			(stroke
				(width 0.1)
				(type default)
			)
			(layer "F.Fab")
		)
		(pad "1" smd circle
			(at -0.40005 0)
			(size 0 0)
			(layers "F.Cu" "F.Mask" "F.Paste")
			(net "FM_JTAG_TCK_MUX_SEL")
		)
		(pad "2" smd circle
			(at 0.40005 0)
			(size 0 0)
			(layers "F.Cu" "F.Mask" "F.Paste")
			(net "GND")
		)
	)
	(footprint ""
		(layer "F.Cu")
		(at 343.776808 -402.371052 -90)
		(property "Reference" "C1552"
			(at 0 0 270)
			(layer "F.SilkS")
			(hide yes)
			(effects
				(font
					(size 1.27 1.27)
				)
			)
		)
		(property "Value" ""
			(at 0 0 270)
			(layer "F.Fab")
			(effects
				(font
					(size 1.27 1.27)
				)
			)
		)
		(duplicate_pad_numbers_are_jumpers no)
		(fp_line
			(start -0.299974 0.150114)
			(end -0.299974 -0.150114)
			(stroke
				(width 0.1)
				(type default)
			)
			(layer "F.Fab")
		)
		(fp_line
			(start 0.299974 0.150114)
			(end -0.299974 0.150114)
			(stroke
				(width 0.1)
				(type default)
			)
			(layer "F.Fab")
		)
		(fp_line
			(start -0.299974 -0.150114)
			(end 0.299974 -0.150114)
			(stroke
				(width 0.1)
				(type default)
			)
			(layer "F.Fab")
		)
		(fp_line
			(start 0.299974 -0.150114)
			(end 0.299974 0.150114)
			(stroke
				(width 0.1)
				(type default)
			)
			(layer "F.Fab")
		)
		(pad "1" smd rect
			(at -0.2667 0 270)
			(size 0.3048 0.381)
			(layers "F.Cu" "F.Mask" "F.Paste")
			(net "P5E_CPU0_PE4_TX_C_DN<13>")
		)
		(pad "2" smd rect
			(at 0.2667 0 270)
			(size 0.3048 0.381)
			(layers "F.Cu" "F.Mask" "F.Paste")
			(net "P5E_CPU0_PE4_TX_DN<13>")
		)
	)
	(footprint ""
		(layer "F.Cu")
		(at 120.066054 -357.11638 90)
		(property "Reference" "PR1340"
			(at 0 0 90)
			(layer "F.SilkS")
			(hide yes)
			(effects
				(font
					(size 1.27 1.27)
				)
			)
		)
		(property "Value" ""
			(at 0 0 90)
			(layer "F.Fab")
			(effects
				(font
					(size 1.27 1.27)
				)
			)
		)
		(duplicate_pad_numbers_are_jumpers no)
		(fp_line
			(start 0.7874 -0.4064)
			(end 0.7874 0.4064)
			(stroke
				(width 0.1524)
				(type default)
			)
			(layer "F.SilkS")
		)
		(fp_line
			(start -0.7874 -0.4064)
			(end 0.7874 -0.4064)
			(stroke
				(width 0.1524)
				(type default)
			)
			(layer "F.SilkS")
		)
		(fp_line
			(start 0.7874 0.4064)
			(end -0.7874 0.4064)
			(stroke
				(width 0.1524)
				(type default)
			)
			(layer "F.SilkS")
		)
		(fp_line
			(start -0.7874 0.4064)
			(end -0.7874 -0.4064)
			(stroke
				(width 0.1524)
				(type default)
			)
			(layer "F.SilkS")
		)
		(fp_line
			(start -0.12065 -0.305054)
			(end -0.12065 -0.2794)
			(stroke
				(width 0.1)
				(type default)
			)
			(layer "F.Fab")
		)
		(fp_line
			(start -0.67945 -0.305054)
			(end -0.12065 -0.305054)
			(stroke
				(width 0.1)
				(type default)
			)
			(layer "F.Fab")
		)
		(fp_line
			(start 0.67945 -0.3048)
			(end 0.67945 0.3048)
			(stroke
				(width 0.1)
				(type default)
			)
			(layer "F.Fab")
		)
		(fp_line
			(start 0.12065 -0.3048)
			(end 0.67945 -0.3048)
			(stroke
				(width 0.1)
				(type default)
			)
			(layer "F.Fab")
		)
		(fp_line
			(start 0.12065 -0.2794)
			(end 0.12065 -0.3048)
			(stroke
				(width 0.1)
				(type default)
			)
			(layer "F.Fab")
		)
		(fp_line
			(start -0.12065 -0.2794)
			(end 0.12065 -0.2794)
			(stroke
				(width 0.1)
				(type default)
			)
			(layer "F.Fab")
		)
		(fp_line
			(start 0.120396 0.2794)
			(end -0.12065 0.2794)
			(stroke
				(width 0.1)
				(type default)
			)
			(layer "F.Fab")
		)
		(fp_line
			(start -0.12065 0.2794)
			(end -0.12065 0.3048)
			(stroke
				(width 0.1)
				(type default)
			)
			(layer "F.Fab")
		)
		(fp_line
			(start 0.67945 0.3048)
			(end 0.120396 0.3048)
			(stroke
				(width 0.1)
				(type default)
			)
			(layer "F.Fab")
		)
		(fp_line
			(start 0.120396 0.3048)
			(end 0.120396 0.2794)
			(stroke
				(width 0.1)
				(type default)
			)
			(layer "F.Fab")
		)
		(fp_line
			(start -0.12065 0.3048)
			(end -0.67945 0.3048)
			(stroke
				(width 0.1)
				(type default)
			)
			(layer "F.Fab")
		)
		(fp_line
			(start -0.67945 0.3048)
			(end -0.67945 -0.305054)
			(stroke
				(width 0.1)
				(type default)
			)
			(layer "F.Fab")
		)
		(pad "1" smd circle
			(at -0.40005 0 90)
			(size 0 0)
			(layers "F.Cu" "F.Mask" "F.Paste")
			(net "PVPP_HBM_CPU1_FB")
		)
		(pad "2" smd circle
			(at 0.40005 0 90)
			(size 0 0)
			(layers "F.Cu" "F.Mask" "F.Paste")
			(net "SH_PVPP_HBM_CPU1_P")
		)
	)
	(footprint ""
		(layer "F.Cu")
		(at 402.02993 -402.371052 -90)
		(property "Reference" "C955"
			(at 0 0 270)
			(layer "F.SilkS")
			(hide yes)
			(effects
				(font
					(size 1.27 1.27)
				)
			)
		)
		(property "Value" ""
			(at 0 0 270)
			(layer "F.Fab")
			(effects
				(font
					(size 1.27 1.27)
				)
			)
		)
		(duplicate_pad_numbers_are_jumpers no)
		(fp_line
			(start -0.299974 0.150114)
			(end -0.299974 -0.150114)
			(stroke
				(width 0.1)
				(type default)
			)
			(layer "F.Fab")
		)
		(fp_line
			(start 0.299974 0.150114)
			(end -0.299974 0.150114)
			(stroke
				(width 0.1)
				(type default)
			)
			(layer "F.Fab")
		)
		(fp_line
			(start -0.299974 -0.150114)
			(end 0.299974 -0.150114)
			(stroke
				(width 0.1)
				(type default)
			)
			(layer "F.Fab")
		)
		(fp_line
			(start 0.299974 -0.150114)
			(end 0.299974 0.150114)
			(stroke
				(width 0.1)
				(type default)
			)
			(layer "F.Fab")
		)
		(pad "1" smd rect
			(at -0.2667 0 270)
			(size 0.3048 0.381)
			(layers "F.Cu" "F.Mask" "F.Paste")
			(net "P5E_CPU0_PE2_TX_C_DP<5>")
		)
		(pad "2" smd rect
			(at 0.2667 0 270)
			(size 0.3048 0.381)
			(layers "F.Cu" "F.Mask" "F.Paste")
			(net "P5E_CPU0_PE2_TX_DP<5>")
		)
	)
	(footprint ""
		(layer "F.Cu")
		(at 124.931424 -361.704382 180)
		(property "Reference" "PC1262"
			(at 0 0 180)
			(layer "F.SilkS")
			(hide yes)
			(effects
				(font
					(size 1.27 1.27)
				)
			)
		)
		(property "Value" ""
			(at 0 0 180)
			(layer "F.Fab")
			(effects
				(font
					(size 1.27 1.27)
				)
			)
		)
		(duplicate_pad_numbers_are_jumpers no)
		(fp_line
			(start 0.7874 0.4064)
			(end -0.7874 0.4064)
			(stroke
				(width 0.1524)
				(type default)
			)
			(layer "F.SilkS")
		)
		(fp_line
			(start 0.7874 -0.4064)
			(end 0.7874 0.4064)
			(stroke
				(width 0.1524)
				(type default)
			)
			(layer "F.SilkS")
		)
		(fp_line
			(start -0.7874 0.4064)
			(end -0.7874 -0.4064)
			(stroke
				(width 0.1524)
				(type default)
			)
			(layer "F.SilkS")
		)
		(fp_line
			(start -0.7874 -0.4064)
			(end 0.7874 -0.4064)
			(stroke
				(width 0.1524)
				(type default)
			)
			(layer "F.SilkS")
		)
		(fp_line
			(start 0.67945 0.3048)
			(end 0.120396 0.3048)
			(stroke
				(width 0.1)
				(type default)
			)
			(layer "F.Fab")
		)
		(fp_line
			(start 0.67945 -0.3048)
			(end 0.67945 0.3048)
			(stroke
				(width 0.1)
				(type default)
			)
			(layer "F.Fab")
		)
		(fp_line
			(start 0.12065 -0.2794)
			(end 0.12065 -0.3048)
			(stroke
				(width 0.1)
				(type default)
			)
			(layer "F.Fab")
		)
		(fp_line
			(start 0.12065 -0.3048)
			(end 0.67945 -0.3048)
			(stroke
				(width 0.1)
				(type default)
			)
			(layer "F.Fab")
		)
		(fp_line
			(start 0.120396 0.3048)
			(end 0.120396 0.2794)
			(stroke
				(width 0.1)
				(type default)
			)
			(layer "F.Fab")
		)
		(fp_line
			(start 0.120396 0.2794)
			(end -0.12065 0.2794)
			(stroke
				(width 0.1)
				(type default)
			)
			(layer "F.Fab")
		)
		(fp_line
			(start -0.12065 0.3048)
			(end -0.67945 0.3048)
			(stroke
				(width 0.1)
				(type default)
			)
			(layer "F.Fab")
		)
		(fp_line
			(start -0.12065 0.2794)
			(end -0.12065 0.3048)
			(stroke
				(width 0.1)
				(type default)
			)
			(layer "F.Fab")
		)
		(fp_line
			(start -0.12065 -0.2794)
			(end 0.12065 -0.2794)
			(stroke
				(width 0.1)
				(type default)
			)
			(layer "F.Fab")
		)
		(fp_line
			(start -0.12065 -0.305054)
			(end -0.12065 -0.2794)
			(stroke
				(width 0.1)
				(type default)
			)
			(layer "F.Fab")
		)
		(fp_line
			(start -0.67945 0.3048)
			(end -0.67945 -0.305054)
			(stroke
				(width 0.1)
				(type default)
			)
			(layer "F.Fab")
		)
		(fp_line
			(start -0.67945 -0.305054)
			(end -0.12065 -0.305054)
			(stroke
				(width 0.1)
				(type default)
			)
			(layer "F.Fab")
		)
		(pad "1" smd circle
			(at -0.40005 0 180)
			(size 0 0)
			(layers "F.Cu" "F.Mask" "F.Paste")
			(net "SW_P12V_PVCCIN_CPU1_FLT")
		)
		(pad "2" smd circle
			(at 0.40005 0 180)
			(size 0 0)
			(layers "F.Cu" "F.Mask" "F.Paste")
			(net "GND")
		)
	)
)
